(kicad_pcb
	(version 20241229)
	(generator "pcbnew")
	(generator_version "9.0")
	(general
		(thickness 1.61)
		(legacy_teardrops no)
	)
	(paper "A3")
	(title_block
		(title "RDIMM DDR5 Tester")
		(date "2026-05-21")
		(rev "2.2.0")
		(company "Antmicro")
		(comment 9 "footprints 128-132 of 796")
	)
	(layers
		(0 "F.Cu" signal)
		(4 "In1.Cu" power)
		(6 "In2.Cu" mixed)
		(8 "In3.Cu" power)
		(10 "In4.Cu" mixed)
		(12 "In5.Cu" power)
		(14 "In6.Cu" mixed)
		(16 "In7.Cu" power)
		(18 "In8.Cu" power)
		(20 "In9.Cu" mixed)
		(22 "In10.Cu" power)
		(2 "B.Cu" signal)
		(9 "F.Adhes" user "F.Adhesive")
		(11 "B.Adhes" user "B.Adhesive")
		(13 "F.Paste" user)
		(15 "B.Paste" user)
		(5 "F.SilkS" user "F.Silkscreen")
		(7 "B.SilkS" user "B.Silkscreen")
		(1 "F.Mask" user)
		(3 "B.Mask" user)
		(17 "Dwgs.User" user "User.Drawings")
		(19 "Cmts.User" user "User.Comments")
		(21 "Eco1.User" user "User.Eco1")
		(23 "Eco2.User" user "User.Eco2")
		(25 "Edge.Cuts" user)
		(27 "Margin" user)
		(31 "F.CrtYd" user "F.Courtyard")
		(29 "B.CrtYd" user "B.Courtyard")
		(35 "F.Fab" user)
		(33 "B.Fab" user)
	)
	(footprint "antmicro-footprints:R_0402_1005Metric"
		(layer "F.Cu")
		(at 119.15 149.61 180)
		(descr "Resistor SMD 0402")
		(tags "resistor SMD 0402")
		(property "Reference" "R24"
			(at -5.11 -0.415 0)
			(layer "F.SilkS")
			(effects
				(font
					(size 0.7 0.7)
					(thickness 0.15)
				)
				(justify right bottom)
			)
		)
		(property "Value" "R_49k9_0402"
			(at -1.011843 1.772047 0)
			(layer "F.Fab")
			(effects
				(font
					(size 0.7 0.7)
					(thickness 0.15)
				)
				(justify right bottom)
			)
		)
		(property "Datasheet" "https://www.bourns.com/docs/product-datasheets/cr.pdf"
			(at 0 0 180)
			(layer "F.Fab")
			(hide yes)
			(effects
				(font
					(size 1.27 1.27)
					(thickness 0.15)
				)
			)
		)
		(property "MPN" "CR0402-FX-4992GLF"
			(at 0 0 180)
			(unlocked yes)
			(layer "F.Fab")
			(hide yes)
			(effects
				(font
					(size 1 1)
					(thickness 0.15)
				)
			)
		)
		(property "Manufacturer" "Bourns"
			(at 0 0 180)
			(unlocked yes)
			(layer "F.Fab")
			(hide yes)
			(effects
				(font
					(size 1 1)
					(thickness 0.15)
				)
			)
		)
		(property "License" "Apache-2.0"
			(at 0 0 180)
			(unlocked yes)
			(layer "F.Fab")
			(hide yes)
			(effects
				(font
					(size 1 1)
					(thickness 0.15)
				)
			)
		)
		(property "Author" "Antmicro"
			(at 0 0 180)
			(unlocked yes)
			(layer "F.Fab")
			(hide yes)
			(effects
				(font
					(size 1 1)
					(thickness 0.15)
				)
			)
		)
		(property "Val" "49k9"
			(at 0 0 180)
			(unlocked yes)
			(layer "F.Fab")
			(hide yes)
			(effects
				(font
					(size 1 1)
					(thickness 0.15)
				)
			)
		)
		(property "Tolerance" "1%"
			(at 0 0 180)
			(unlocked yes)
			(layer "F.Fab")
			(hide yes)
			(effects
				(font
					(size 1 1)
					(thickness 0.15)
				)
			)
		)
		(sheetname "/HDMI + SD Card/")
		(sheetfile "hdmi-sd-card.kicad_sch")
		(attr smd)
		(fp_rect
			(start -0.925 -0.47)
			(end 0.925 0.47)
			(stroke
				(width 0.05)
				(type default)
			)
			(fill no)
			(layer "F.CrtYd")
		)
		(fp_rect
			(start -0.5 -0.25)
			(end 0.5 0.25)
			(stroke
				(width 0.15)
				(type solid)
			)
			(fill no)
			(layer "F.Fab")
		)
		(fp_text user "${REFERENCE}"
			(at -0.95 3.168 180)
			(layer "F.Fab")
			(effects
				(font
					(size 0.7 0.7)
					(thickness 0.15)
				)
				(justify left bottom)
			)
		)
		(fp_text user "License: Apache-2.0"
			(at -0.95 5.169 180)
			(layer "F.Fab")
			(effects
				(font
					(size 0.7 0.7)
					(thickness 0.15)
				)
				(justify left bottom)
			)
		)
		(fp_text user "Author: Antmicro"
			(at -0.95 4.169 180)
			(layer "F.Fab")
			(effects
				(font
					(size 0.7 0.7)
					(thickness 0.15)
				)
				(justify left bottom)
			)
		)
		(pad "1" smd roundrect
			(at -0.48 0 180)
			(size 0.59 0.64)
			(layers "F.Cu" "F.Mask" "F.Paste")
			(roundrect_rratio 0.25)
			(net 673 "Net-(L3-Pad2)")
			(pintype "passive")
		)
		(pad "2" smd roundrect
			(at 0.48 0 180)
			(size 0.59 0.64)
			(layers "F.Cu" "F.Mask" "F.Paste")
			(roundrect_rratio 0.25)
			(net 322 "Net-(C300-Pad2)")
			(pintype "passive")
		)
	)
	(footprint "antmicro-footprints:L_0402_1005Metric"
		(layer "F.Cu")
		(at 121.025 152.61 180)
		(descr "Inductor SMD 0402")
		(tags "Inductor SMD 0402")
		(property "Reference" "L9"
			(at -5.425 -0.415 0)
			(layer "F.SilkS")
			(effects
				(font
					(size 0.7 0.7)
					(thickness 0.15)
				)
				(justify right bottom)
			)
		)
		(property "Value" "L_20n_0.35A_0402"
			(at 0 1.4 0)
			(layer "F.Fab")
			(effects
				(font
					(size 0.7 0.7)
					(thickness 0.15)
				)
				(justify right bottom)
			)
		)
		(property "Datasheet" "https://product.tdk.com/system/files/dam/doc/product/inductor/inductor/smd/catalog/inductor_automotive_high-frequency_mlg1005s_en.pdf?ref_disty=mouser"
			(at 0 0 180)
			(layer "F.Fab")
			(hide yes)
			(effects
				(font
					(size 1.27 1.27)
					(thickness 0.15)
				)
			)
		)
		(property "Val" "20n/0.35A"
			(at 0 0 180)
			(unlocked yes)
			(layer "F.Fab")
			(hide yes)
			(effects
				(font
					(size 1 1)
					(thickness 0.15)
				)
			)
		)
		(property "Manufacturer" "TDK"
			(at 0 0 180)
			(unlocked yes)
			(layer "F.Fab")
			(hide yes)
			(effects
				(font
					(size 1 1)
					(thickness 0.15)
				)
			)
		)
		(property "MPN" "MLG1005S20NJTD25"
			(at 0 0 180)
			(unlocked yes)
			(layer "F.Fab")
			(hide yes)
			(effects
				(font
					(size 1 1)
					(thickness 0.15)
				)
			)
		)
		(property "ISat" ""
			(at 0 0 180)
			(unlocked yes)
			(layer "F.Fab")
			(hide yes)
			(effects
				(font
					(size 1 1)
					(thickness 0.15)
				)
			)
		)
		(property "IMax" "0.35 A"
			(at 0 0 180)
			(unlocked yes)
			(layer "F.Fab")
			(hide yes)
			(effects
				(font
					(size 1 1)
					(thickness 0.15)
				)
			)
		)
		(property "Size" "1.0x0.5"
			(at 0 0 180)
			(unlocked yes)
			(layer "F.Fab")
			(hide yes)
			(effects
				(font
					(size 1 1)
					(thickness 0.15)
				)
			)
		)
		(property "Author" "Antmicro"
			(at 0 0 180)
			(unlocked yes)
			(layer "F.Fab")
			(hide yes)
			(effects
				(font
					(size 1 1)
					(thickness 0.15)
				)
			)
		)
		(property "License" "Apache-2.0"
			(at 0 0 180)
			(unlocked yes)
			(layer "F.Fab")
			(hide yes)
			(effects
				(font
					(size 1 1)
					(thickness 0.15)
				)
			)
		)
		(sheetname "/HDMI + SD Card/")
		(sheetfile "hdmi-sd-card.kicad_sch")
		(attr smd)
		(fp_rect
			(start -0.925 -0.47)
			(end 0.925 0.47)
			(stroke
				(width 0.05)
				(type default)
			)
			(fill no)
			(layer "F.CrtYd")
		)
		(fp_rect
			(start -0.499 -0.249)
			(end 0.499 0.249)
			(stroke
				(width 0.15)
				(type solid)
			)
			(fill no)
			(layer "F.Fab")
		)
		(fp_text user "License: Apache-2.0"
			(at -0.932 5.17 180)
			(layer "F.Fab")
			(effects
				(font
					(size 0.7 0.7)
					(thickness 0.15)
				)
				(justify left bottom)
			)
		)
		(fp_text user "${REFERENCE}"
			(at -0.932 3.168 180)
			(layer "F.Fab")
			(effects
				(font
					(size 0.7 0.7)
					(thickness 0.15)
				)
				(justify left bottom)
			)
		)
		(fp_text user "Author: Antmicro"
			(at -0.932 4.17 180)
			(layer "F.Fab")
			(effects
				(font
					(size 0.7 0.7)
					(thickness 0.15)
				)
				(justify left bottom)
			)
		)
		(pad "1" smd roundrect
			(at -0.48 0 180)
			(size 0.59 0.64)
			(layers "F.Cu" "F.Mask" "F.Paste")
			(roundrect_rratio 0.25)
			(net 349 "/FPGA MGT Interface/HDMI_IN.D0_N")
			(pintype "passive")
		)
		(pad "2" smd roundrect
			(at 0.48 0 180)
			(size 0.59 0.64)
			(layers "F.Cu" "F.Mask" "F.Paste")
			(roundrect_rratio 0.25)
			(net 679 "Net-(L9-Pad2)")
			(pintype "passive")
		)
	)
	(footprint "antmicro-footprints:Mech_Lightpipe_Mentor_1296.2013"
		(layer "F.Cu")
		(at 107.185 114.725 90)
		(property "Reference" "H2"
			(at 0 -0.5 180)
			(unlocked yes)
			(layer "F.SilkS")
			(hide yes)
			(effects
				(font
					(size 0.7 0.7)
					(thickness 0.15)
				)
				(justify left bottom)
			)
		)
		(property "Value" "Lightpipe_Mentor_1296.2013"
			(at -1.75 6.25 90)
			(unlocked yes)
			(layer "F.Fab")
			(effects
				(font
					(size 0.7 0.7)
					(thickness 0.15)
				)
				(justify left bottom)
			)
		)
		(property "Datasheet" "https://docs.rs-online.com/e47b/0900766b813f6efb.pdf"
			(at 0 0 90)
			(layer "F.Fab")
			(hide yes)
			(effects
				(font
					(size 1.27 1.27)
					(thickness 0.15)
				)
			)
		)
		(property "Manufacturer" "Mentor Worldwide"
			(at 0 0 90)
			(unlocked yes)
			(layer "F.Fab")
			(hide yes)
			(effects
				(font
					(size 1 1)
					(thickness 0.15)
				)
			)
		)
		(property "MPN" "1296.2013"
			(at 0 0 90)
			(unlocked yes)
			(layer "F.Fab")
			(hide yes)
			(effects
				(font
					(size 1 1)
					(thickness 0.15)
				)
			)
		)
		(property "Author" "Antmicro"
			(at 0 0 90)
			(unlocked yes)
			(layer "F.Fab")
			(hide yes)
			(effects
				(font
					(size 1 1)
					(thickness 0.15)
				)
			)
		)
		(property "License" "Apache-2.0"
			(at 0 0 90)
			(unlocked yes)
			(layer "F.Fab")
			(hide yes)
			(effects
				(font
					(size 1 1)
					(thickness 0.15)
				)
			)
		)
		(sheetname "/")
		(sheetfile "data-center-rdimm-ddr5-tester.kicad_sch")
		(attr exclude_from_pos_files)
		(fp_rect
			(start -1.508 -6.335)
			(end 1.507 5.289)
			(stroke
				(width 0.15)
				(type solid)
			)
			(fill no)
			(layer "F.SilkS")
		)
		(fp_text user "License: Apache-2.0"
			(at -1.75 10.25 90)
			(layer "F.Fab")
			(effects
				(font
					(size 0.7 0.7)
					(thickness 0.15)
				)
				(justify left bottom)
			)
		)
		(fp_text user "${REFERENCE}"
			(at -1.75 7.5 90)
			(layer "F.Fab")
			(effects
				(font
					(size 0.7 0.7)
					(thickness 0.15)
				)
				(justify left bottom)
			)
		)
		(fp_text user "Author: Antmicro"
			(at -1.75 8.75 90)
			(layer "F.Fab")
			(effects
				(font
					(size 0.7 0.7)
					(thickness 0.15)
				)
				(justify left bottom)
			)
		)
		(pad "" np_thru_hole circle
			(at 0 -4.96 90)
			(size 1.2 1.2)
			(drill 1.2)
			(layers "*.Cu" "*.Mask")
		)
		(pad "" np_thru_hole circle
			(at 0 4.24 90)
			(size 1.2 1.2)
			(drill 1.2)
			(layers "*.Cu" "*.Mask")
		)
	)
	(footprint "antmicro-footprints:SOT-323"
		(layer "F.Cu")
		(at 119.43 139.53 -90)
		(property "Reference" "Q20"
			(at 0 -2.5 90)
			(layer "F.SilkS")
			(effects
				(font
					(size 0.7 0.7)
					(thickness 0.15)
				)
				(justify right bottom)
			)
		)
		(property "Value" "BSS84AKW"
			(at 0 2.749 90)
			(layer "F.Fab")
			(effects
				(font
					(size 0.7 0.7)
					(thickness 0.15)
				)
				(justify right bottom)
			)
		)
		(property "Datasheet" "https://assets.nexperia.com/documents/data-sheet/BSS84AKW.pdf"
			(at 0 0 270)
			(layer "F.Fab")
			(hide yes)
			(effects
				(font
					(size 1.27 1.27)
					(thickness 0.15)
				)
			)
		)
		(property "MPN" "BSS84AKW,115"
			(at 0 0 270)
			(unlocked yes)
			(layer "F.Fab")
			(hide yes)
			(effects
				(font
					(size 1 1)
					(thickness 0.15)
				)
			)
		)
		(property "Manufacturer" "Nexperia"
			(at 0 0 270)
			(unlocked yes)
			(layer "F.Fab")
			(hide yes)
			(effects
				(font
					(size 1 1)
					(thickness 0.15)
				)
			)
		)
		(property "Author" "Antmicro"
			(at 0 0 270)
			(unlocked yes)
			(layer "F.Fab")
			(hide yes)
			(effects
				(font
					(size 1 1)
					(thickness 0.15)
				)
			)
		)
		(property "License" "Apache-2.0"
			(at 0 0 270)
			(unlocked yes)
			(layer "F.Fab")
			(hide yes)
			(effects
				(font
					(size 1 1)
					(thickness 0.15)
				)
			)
		)
		(sheetname "/Debug FTDI + VNA/")
		(sheetfile "debug-ftdi.kicad_sch")
		(attr smd)
		(fp_line
			(start -0.802 1.199)
			(end -0.5 1.199)
			(stroke
				(width 0.15)
				(type solid)
			)
			(layer "F.SilkS")
		)
		(fp_line
			(start 0.498 1.199)
			(end 0.8 1.199)
			(stroke
				(width 0.15)
				(type solid)
			)
			(layer "F.SilkS")
		)
		(fp_line
			(start 0.8 1.199)
			(end 0.8 0.9)
			(stroke
				(width 0.15)
				(type solid)
			)
			(layer "F.SilkS")
		)
		(fp_line
			(start -0.802 1.05)
			(end -0.802 1.199)
			(stroke
				(width 0.15)
				(type solid)
			)
			(layer "F.SilkS")
		)
		(fp_line
			(start -0.802 -1.2)
			(end -0.802 -1.05)
			(stroke
				(width 0.15)
				(type solid)
			)
			(layer "F.SilkS")
		)
		(fp_line
			(start -0.402 -1.2)
			(end -0.802 -1.2)
			(stroke
				(width 0.15)
				(type solid)
			)
			(layer "F.SilkS")
		)
		(fp_line
			(start 0.498 -1.2)
			(end 0.8 -1.2)
			(stroke
				(width 0.15)
				(type solid)
			)
			(layer "F.SilkS")
		)
		(fp_line
			(start 0.8 -1.2)
			(end 0.8 -0.902)
			(stroke
				(width 0.15)
				(type solid)
			)
			(layer "F.SilkS")
		)
		(fp_circle
			(center -1.05 -1.156824)
			(end -1 -1.129824)
			(stroke
				(width 0.15)
				(type solid)
			)
			(fill no)
			(layer "F.SilkS")
		)
		(fp_rect
			(start -1.35 -1.35)
			(end 1.35 1.35)
			(stroke
				(width 0.05)
				(type solid)
			)
			(fill no)
			(layer "F.CrtYd")
		)
		(fp_line
			(start -0.677 1.1)
			(end 0.675 1.1)
			(stroke
				(width 0.15)
				(type solid)
			)
			(layer "F.Fab")
		)
		(fp_line
			(start -0.677 -1.101)
			(end -0.677 1.1)
			(stroke
				(width 0.15)
				(type solid)
			)
			(layer "F.Fab")
		)
		(fp_line
			(start -0.677 -1.101)
			(end 0.675 -1.101)
			(stroke
				(width 0.15)
				(type solid)
			)
			(layer "F.Fab")
		)
		(fp_line
			(start 0.675 -1.101)
			(end 0.675 1.1)
			(stroke
				(width 0.15)
				(type solid)
			)
			(layer "F.Fab")
		)
		(fp_text user "${REFERENCE}"
			(at -1.35 4.749 270)
			(layer "F.Fab")
			(effects
				(font
					(size 0.7 0.7)
					(thickness 0.15)
				)
				(justify left bottom)
			)
		)
		(fp_text user "License: Apache-2.0"
			(at -1.35 5.949 270)
			(layer "F.Fab")
			(effects
				(font
					(size 0.7 0.7)
					(thickness 0.15)
				)
				(justify left bottom)
			)
		)
		(fp_text user "Author: Antmicro"
			(at -1.35 7.149 270)
			(layer "F.Fab")
			(effects
				(font
					(size 0.7 0.7)
					(thickness 0.15)
				)
				(justify left bottom)
			)
		)
		(pad "1" smd rect
			(at -0.927 -0.652 270)
			(size 0.55 0.6)
			(layers "F.Cu" "F.Mask" "F.Paste")
			(net 372 "/Debug FTDI + VNA/FTDI_PWREN")
			(pinfunction "G")
			(pintype "bidirectional")
		)
		(pad "2" smd rect
			(at -0.927 0.65 270)
			(size 0.55 0.6)
			(layers "F.Cu" "F.Mask" "F.Paste")
			(net 6 "/Debug FTDI + VNA/FTDI_3V3")
			(pinfunction "S")
			(pintype "bidirectional")
		)
		(pad "3" smd rect
			(at 0.925 0 270)
			(size 0.55 0.6)
			(layers "F.Cu" "F.Mask" "F.Paste")
			(net 818 "Net-(D17-A)")
			(pinfunction "D")
			(pintype "bidirectional")
		)
	)
	(footprint "antmicro-footprints:R_0402_1005Metric"
		(layer "F.Cu")
		(at 108.824499 145.796)
		(descr "Resistor SMD 0402")
		(tags "resistor SMD 0402")
		(property "Reference" "R69"
			(at 1.125501 0.504 0)
			(layer "F.SilkS")
			(effects
				(font
					(size 0.7 0.7)
					(thickness 0.15)
				)
				(justify left bottom)
			)
		)
		(property "Value" "R_5k11_0402"
			(at -1.011843 1.772047 0)
			(layer "F.Fab")
			(effects
				(font
					(size 0.7 0.7)
					(thickness 0.15)
				)
				(justify left bottom)
			)
		)
		(property "Datasheet" "https://www.bourns.com/docs/product-datasheets/cr.pdf"
			(at 0 0 0)
			(layer "F.Fab")
			(hide yes)
			(effects
				(font
					(size 1.27 1.27)
					(thickness 0.15)
				)
			)
		)
		(property "Manufacturer" "Bourns"
			(at 0 0 0)
			(unlocked yes)
			(layer "F.Fab")
			(hide yes)
			(effects
				(font
					(size 1 1)
					(thickness 0.15)
				)
			)
		)
		(property "MPN" "CR0402-FX-5111GLF"
			(at 0 0 0)
			(unlocked yes)
			(layer "F.Fab")
			(hide yes)
			(effects
				(font
					(size 1 1)
					(thickness 0.15)
				)
			)
		)
		(property "Val" "5k11"
			(at 0 0 0)
			(unlocked yes)
			(layer "F.Fab")
			(hide yes)
			(effects
				(font
					(size 1 1)
					(thickness 0.15)
				)
			)
		)
		(property "License" "Apache-2.0"
			(at 0 0 0)
			(unlocked yes)
			(layer "F.Fab")
			(hide yes)
			(effects
				(font
					(size 1 1)
					(thickness 0.15)
				)
			)
		)
		(property "Author" "Antmicro"
			(at 0 0 0)
			(unlocked yes)
			(layer "F.Fab")
			(hide yes)
			(effects
				(font
					(size 1 1)
					(thickness 0.15)
				)
			)
		)
		(property "Tolerance" "1%"
			(at 0 0 0)
			(unlocked yes)
			(layer "F.Fab")
			(hide yes)
			(effects
				(font
					(size 1 1)
					(thickness 0.15)
				)
			)
		)
		(sheetname "/Debug FTDI + VNA/")
		(sheetfile "debug-ftdi.kicad_sch")
		(attr smd)
		(fp_rect
			(start -0.925 -0.47)
			(end 0.925 0.47)
			(stroke
				(width 0.05)
				(type default)
			)
			(fill no)
			(layer "F.CrtYd")
		)
		(fp_rect
			(start -0.5 -0.25)
			(end 0.5 0.25)
			(stroke
				(width 0.15)
				(type solid)
			)
			(fill no)
			(layer "F.Fab")
		)
		(fp_text user "License: Apache-2.0"
			(at -0.95 5.169 0)
			(layer "F.Fab")
			(effects
				(font
					(size 0.7 0.7)
					(thickness 0.15)
				)
				(justify left bottom)
			)
		)
		(fp_text user "Author: Antmicro"
			(at -0.95 4.169 0)
			(layer "F.Fab")
			(effects
				(font
					(size 0.7 0.7)
					(thickness 0.15)
				)
				(justify left bottom)
			)
		)
		(fp_text user "${REFERENCE}"
			(at -0.95 3.168 0)
			(layer "F.Fab")
			(effects
				(font
					(size 0.7 0.7)
					(thickness 0.15)
				)
				(justify left bottom)
			)
		)
		(pad "1" smd roundrect
			(at -0.48 0)
			(size 0.59 0.64)
			(layers "F.Cu" "F.Mask" "F.Paste")
			(roundrect_rratio 0.25)
			(net 366 "/Debug FTDI + VNA/CC2")
			(pintype "passive")
		)
		(pad "2" smd roundrect
			(at 0.48 0)
			(size 0.59 0.64)
			(layers "F.Cu" "F.Mask" "F.Paste")
			(roundrect_rratio 0.25)
			(net 1 "GND")
			(pintype "passive")
		)
	)
)
